(kicad_pcb
	(version 20260206)
	(generator "pcbnew")
	(generator_version "10.0")
	(general
		(thickness 1.6)
		(legacy_teardrops no)
	)
	(paper "A4")
	(title_block
		(title "04192023_DAF0TMB3IC0_F0TG_MB_C_brd_V02_OCP.brd")
		(comment 1 "Grand Teton / footprints 2336-2342 of 8354")
	)
	(layers
		(0 "F.Cu" signal "TOP")
		(4 "In1.Cu" signal "GND")
		(6 "In2.Cu" signal "IN1")
		(8 "In3.Cu" signal "GND1")
		(10 "In4.Cu" signal "IN2")
		(12 "In5.Cu" signal "GND2")
		(14 "In6.Cu" signal "IN3")
		(16 "In7.Cu" signal "GND3")
		(18 "In8.Cu" signal "VCC")
		(20 "In9.Cu" signal "VCC1")
		(22 "In10.Cu" signal "GND4")
		(24 "In11.Cu" signal "IN4")
		(26 "In12.Cu" signal "GND5")
		(28 "In13.Cu" signal "IN5")
		(30 "In14.Cu" signal "GND6")
		(32 "In15.Cu" signal "IN6")
		(34 "In16.Cu" signal "GND7")
		(2 "B.Cu" signal "BOTTOM")
		(9 "F.Adhes" user "F.Adhesive")
		(11 "B.Adhes" user "B.Adhesive")
		(13 "F.Paste" user "Package Geometry/Pastemask Top")
		(15 "B.Paste" user "Package Geometry/Pastemask Bottom")
		(5 "F.SilkS" user "Ref Des/Silkscreen Top")
		(7 "B.SilkS" user "Ref Des/Silkscreen Bottom")
		(1 "F.Mask" user "Board Geometry/Soldermask Top")
		(3 "B.Mask" user "Board Geometry/Soldermask Bottom")
		(17 "Dwgs.User" user "User.Drawings")
		(19 "Cmts.User" user "User.Comments")
		(21 "Eco1.User" user "User.Eco1")
		(23 "Eco2.User" user "User.Eco2")
		(25 "Edge.Cuts" user "Board Geometry/Outline")
		(27 "Margin" user)
		(31 "F.CrtYd" user "Package Geometry/Place Bound Top")
		(29 "B.CrtYd" user "Package Geometry/Place Bound Bottom")
		(35 "F.Fab" user "Ref Des/Assembly Top")
		(33 "B.Fab" user "Ref Des/Assembly Bottom")
	)
	(footprint ""
		(layer "F.Cu")
		(at 163.703 -123.952 180)
		(property "Reference" "R439"
			(at 0 0 180)
			(layer "F.SilkS")
			(hide yes)
			(effects
				(font
					(size 1.27 1.27)
				)
			)
		)
		(property "Value" ""
			(at 0 0 180)
			(layer "F.Fab")
			(effects
				(font
					(size 1.27 1.27)
				)
			)
		)
		(duplicate_pad_numbers_are_jumpers no)
		(fp_line
			(start 0.7874 0.4064)
			(end -0.7874 0.4064)
			(stroke
				(width 0.1524)
				(type default)
			)
			(layer "F.SilkS")
		)
		(fp_line
			(start 0.7874 -0.4064)
			(end 0.7874 0.4064)
			(stroke
				(width 0.1524)
				(type default)
			)
			(layer "F.SilkS")
		)
		(fp_line
			(start -0.7874 0.4064)
			(end -0.7874 -0.4064)
			(stroke
				(width 0.1524)
				(type default)
			)
			(layer "F.SilkS")
		)
		(fp_line
			(start -0.7874 -0.4064)
			(end 0.7874 -0.4064)
			(stroke
				(width 0.1524)
				(type default)
			)
			(layer "F.SilkS")
		)
		(fp_line
			(start 0.67945 0.3048)
			(end 0.120396 0.3048)
			(stroke
				(width 0.1)
				(type default)
			)
			(layer "F.Fab")
		)
		(fp_line
			(start 0.67945 -0.3048)
			(end 0.67945 0.3048)
			(stroke
				(width 0.1)
				(type default)
			)
			(layer "F.Fab")
		)
		(fp_line
			(start 0.12065 -0.2794)
			(end 0.12065 -0.3048)
			(stroke
				(width 0.1)
				(type default)
			)
			(layer "F.Fab")
		)
		(fp_line
			(start 0.12065 -0.3048)
			(end 0.67945 -0.3048)
			(stroke
				(width 0.1)
				(type default)
			)
			(layer "F.Fab")
		)
		(fp_line
			(start 0.120396 0.3048)
			(end 0.120396 0.2794)
			(stroke
				(width 0.1)
				(type default)
			)
			(layer "F.Fab")
		)
		(fp_line
			(start 0.120396 0.2794)
			(end -0.12065 0.2794)
			(stroke
				(width 0.1)
				(type default)
			)
			(layer "F.Fab")
		)
		(fp_line
			(start -0.12065 0.3048)
			(end -0.67945 0.3048)
			(stroke
				(width 0.1)
				(type default)
			)
			(layer "F.Fab")
		)
		(fp_line
			(start -0.12065 0.2794)
			(end -0.12065 0.3048)
			(stroke
				(width 0.1)
				(type default)
			)
			(layer "F.Fab")
		)
		(fp_line
			(start -0.12065 -0.2794)
			(end 0.12065 -0.2794)
			(stroke
				(width 0.1)
				(type default)
			)
			(layer "F.Fab")
		)
		(fp_line
			(start -0.12065 -0.305054)
			(end -0.12065 -0.2794)
			(stroke
				(width 0.1)
				(type default)
			)
			(layer "F.Fab")
		)
		(fp_line
			(start -0.67945 0.3048)
			(end -0.67945 -0.305054)
			(stroke
				(width 0.1)
				(type default)
			)
			(layer "F.Fab")
		)
		(fp_line
			(start -0.67945 -0.305054)
			(end -0.12065 -0.305054)
			(stroke
				(width 0.1)
				(type default)
			)
			(layer "F.Fab")
		)
		(pad "1" smd circle
			(at -0.40005 0 180)
			(size 0 0)
			(layers "F.Cu" "F.Mask" "F.Paste")
			(net "PWRGD_P5V")
		)
		(pad "2" smd circle
			(at 0.40005 0 180)
			(size 0 0)
			(layers "F.Cu" "F.Mask" "F.Paste")
			(net "PWRGD_P5V_R2")
		)
	)
	(footprint ""
		(layer "F.Cu")
		(at 29.954982 -153.765504)
		(property "Reference" "H127"
			(at 5.884164 4.9022 0)
			(unlocked yes)
			(layer "F.SilkS")
			(effects
				(font
					(size 0.7874 0.5842)
					(thickness 0.1524)
				)
				(justify left)
			)
		)
		(property "Value" ""
			(at 0 0 0)
			(layer "F.Fab")
			(effects
				(font
					(size 1.27 1.27)
				)
			)
		)
		(duplicate_pad_numbers_are_jumpers no)
		(fp_circle
			(center 0 0)
			(end 5.8166 0)
			(stroke
				(width 0.1524)
				(type default)
			)
			(fill no)
			(layer "F.SilkS")
		)
		(fp_circle
			(center 0 0)
			(end 5.8166 0)
			(stroke
				(width 0.1524)
				(type default)
			)
			(fill no)
			(layer "B.SilkS")
		)
		(fp_circle
			(center 0 0)
			(end 5.8166 0)
			(stroke
				(width 0.1)
				(type default)
			)
			(fill no)
			(layer "B.Fab")
		)
		(fp_circle
			(center 0 0)
			(end 5.8166 0)
			(stroke
				(width 0.1)
				(type default)
			)
			(fill no)
			(layer "F.Fab")
		)
		(pad "" np_thru_hole circle
			(at 0 0)
			(size 10.0076 10.0076)
			(drill 10.0076)
			(layers "*.Cu" "*.Mask")
			(clearance 0.381)
			(thermal_gap 0.381)
		)
	)
	(footprint ""
		(layer "F.Cu")
		(at 271.085056 -123.86437 180)
		(property "Reference" "R3712"
			(at 0 0 180)
			(layer "F.SilkS")
			(hide yes)
			(effects
				(font
					(size 1.27 1.27)
				)
			)
		)
		(property "Value" ""
			(at 0 0 180)
			(layer "F.Fab")
			(effects
				(font
					(size 1.27 1.27)
				)
			)
		)
		(duplicate_pad_numbers_are_jumpers no)
		(fp_line
			(start 0.7874 0.4064)
			(end -0.7874 0.4064)
			(stroke
				(width 0.1524)
				(type default)
			)
			(layer "F.SilkS")
		)
		(fp_line
			(start 0.7874 -0.4064)
			(end 0.7874 0.4064)
			(stroke
				(width 0.1524)
				(type default)
			)
			(layer "F.SilkS")
		)
		(fp_line
			(start -0.7874 0.4064)
			(end -0.7874 -0.4064)
			(stroke
				(width 0.1524)
				(type default)
			)
			(layer "F.SilkS")
		)
		(fp_line
			(start -0.7874 -0.4064)
			(end 0.7874 -0.4064)
			(stroke
				(width 0.1524)
				(type default)
			)
			(layer "F.SilkS")
		)
		(fp_line
			(start 0.67945 0.3048)
			(end 0.120396 0.3048)
			(stroke
				(width 0.1)
				(type default)
			)
			(layer "F.Fab")
		)
		(fp_line
			(start 0.67945 -0.3048)
			(end 0.67945 0.3048)
			(stroke
				(width 0.1)
				(type default)
			)
			(layer "F.Fab")
		)
		(fp_line
			(start 0.12065 -0.2794)
			(end 0.12065 -0.3048)
			(stroke
				(width 0.1)
				(type default)
			)
			(layer "F.Fab")
		)
		(fp_line
			(start 0.12065 -0.3048)
			(end 0.67945 -0.3048)
			(stroke
				(width 0.1)
				(type default)
			)
			(layer "F.Fab")
		)
		(fp_line
			(start 0.120396 0.3048)
			(end 0.120396 0.2794)
			(stroke
				(width 0.1)
				(type default)
			)
			(layer "F.Fab")
		)
		(fp_line
			(start 0.120396 0.2794)
			(end -0.12065 0.2794)
			(stroke
				(width 0.1)
				(type default)
			)
			(layer "F.Fab")
		)
		(fp_line
			(start -0.12065 0.3048)
			(end -0.67945 0.3048)
			(stroke
				(width 0.1)
				(type default)
			)
			(layer "F.Fab")
		)
		(fp_line
			(start -0.12065 0.2794)
			(end -0.12065 0.3048)
			(stroke
				(width 0.1)
				(type default)
			)
			(layer "F.Fab")
		)
		(fp_line
			(start -0.12065 -0.2794)
			(end 0.12065 -0.2794)
			(stroke
				(width 0.1)
				(type default)
			)
			(layer "F.Fab")
		)
		(fp_line
			(start -0.12065 -0.305054)
			(end -0.12065 -0.2794)
			(stroke
				(width 0.1)
				(type default)
			)
			(layer "F.Fab")
		)
		(fp_line
			(start -0.67945 0.3048)
			(end -0.67945 -0.305054)
			(stroke
				(width 0.1)
				(type default)
			)
			(layer "F.Fab")
		)
		(fp_line
			(start -0.67945 -0.305054)
			(end -0.12065 -0.305054)
			(stroke
				(width 0.1)
				(type default)
			)
			(layer "F.Fab")
		)
		(pad "1" smd circle
			(at -0.40005 0 180)
			(size 0 0)
			(layers "F.Cu" "F.Mask" "F.Paste")
			(net "SMB_VR_SENSOR_3V3AUX_SDA")
		)
		(pad "2" smd circle
			(at 0.40005 0 180)
			(size 0 0)
			(layers "F.Cu" "F.Mask" "F.Paste")
			(net "SMB_VR_SENSOR_3V3AUX_SDA_R")
		)
	)
	(footprint ""
		(layer "F.Cu")
		(at 181.737 -100.294948 90)
		(property "Reference" "R231"
			(at 0 0 90)
			(layer "F.SilkS")
			(hide yes)
			(effects
				(font
					(size 1.27 1.27)
				)
			)
		)
		(property "Value" ""
			(at 0 0 90)
			(layer "F.Fab")
			(effects
				(font
					(size 1.27 1.27)
				)
			)
		)
		(duplicate_pad_numbers_are_jumpers no)
		(fp_line
			(start 0.7874 -0.4064)
			(end 0.7874 0.4064)
			(stroke
				(width 0.1524)
				(type default)
			)
			(layer "F.SilkS")
		)
		(fp_line
			(start -0.7874 -0.4064)
			(end 0.7874 -0.4064)
			(stroke
				(width 0.1524)
				(type default)
			)
			(layer "F.SilkS")
		)
		(fp_line
			(start 0.7874 0.4064)
			(end -0.7874 0.4064)
			(stroke
				(width 0.1524)
				(type default)
			)
			(layer "F.SilkS")
		)
		(fp_line
			(start -0.7874 0.4064)
			(end -0.7874 -0.4064)
			(stroke
				(width 0.1524)
				(type default)
			)
			(layer "F.SilkS")
		)
		(fp_line
			(start -0.12065 -0.305054)
			(end -0.12065 -0.2794)
			(stroke
				(width 0.1)
				(type default)
			)
			(layer "F.Fab")
		)
		(fp_line
			(start -0.67945 -0.305054)
			(end -0.12065 -0.305054)
			(stroke
				(width 0.1)
				(type default)
			)
			(layer "F.Fab")
		)
		(fp_line
			(start 0.67945 -0.3048)
			(end 0.67945 0.3048)
			(stroke
				(width 0.1)
				(type default)
			)
			(layer "F.Fab")
		)
		(fp_line
			(start 0.12065 -0.3048)
			(end 0.67945 -0.3048)
			(stroke
				(width 0.1)
				(type default)
			)
			(layer "F.Fab")
		)
		(fp_line
			(start 0.12065 -0.2794)
			(end 0.12065 -0.3048)
			(stroke
				(width 0.1)
				(type default)
			)
			(layer "F.Fab")
		)
		(fp_line
			(start -0.12065 -0.2794)
			(end 0.12065 -0.2794)
			(stroke
				(width 0.1)
				(type default)
			)
			(layer "F.Fab")
		)
		(fp_line
			(start 0.120396 0.2794)
			(end -0.12065 0.2794)
			(stroke
				(width 0.1)
				(type default)
			)
			(layer "F.Fab")
		)
		(fp_line
			(start -0.12065 0.2794)
			(end -0.12065 0.3048)
			(stroke
				(width 0.1)
				(type default)
			)
			(layer "F.Fab")
		)
		(fp_line
			(start 0.67945 0.3048)
			(end 0.120396 0.3048)
			(stroke
				(width 0.1)
				(type default)
			)
			(layer "F.Fab")
		)
		(fp_line
			(start 0.120396 0.3048)
			(end 0.120396 0.2794)
			(stroke
				(width 0.1)
				(type default)
			)
			(layer "F.Fab")
		)
		(fp_line
			(start -0.12065 0.3048)
			(end -0.67945 0.3048)
			(stroke
				(width 0.1)
				(type default)
			)
			(layer "F.Fab")
		)
		(fp_line
			(start -0.67945 0.3048)
			(end -0.67945 -0.305054)
			(stroke
				(width 0.1)
				(type default)
			)
			(layer "F.Fab")
		)
		(pad "1" smd circle
			(at -0.40005 0 90)
			(size 0 0)
			(layers "F.Cu" "F.Mask" "F.Paste")
			(net "PVDDCR_CPU0_P0_OCP_N")
		)
		(pad "2" smd circle
			(at 0.40005 0 90)
			(size 0 0)
			(layers "F.Cu" "F.Mask" "F.Paste")
			(net "FM_PVDDCR_CPU0_P0_OCP_N")
		)
	)
	(footprint ""
		(layer "F.Cu")
		(at 34.18713 -351.578672 90)
		(property "Reference" "PC620_9"
			(at 0 0 90)
			(layer "F.SilkS")
			(hide yes)
			(effects
				(font
					(size 1.27 1.27)
				)
			)
		)
		(property "Value" ""
			(at 0 0 90)
			(layer "F.Fab")
			(effects
				(font
					(size 1.27 1.27)
				)
			)
		)
		(duplicate_pad_numbers_are_jumpers no)
		(fp_line
			(start 0.7874 -0.4064)
			(end 0.7874 0.4064)
			(stroke
				(width 0.1524)
				(type default)
			)
			(layer "F.SilkS")
		)
		(fp_line
			(start -0.7874 -0.4064)
			(end 0.7874 -0.4064)
			(stroke
				(width 0.1524)
				(type default)
			)
			(layer "F.SilkS")
		)
		(fp_line
			(start 0.7874 0.4064)
			(end -0.7874 0.4064)
			(stroke
				(width 0.1524)
				(type default)
			)
			(layer "F.SilkS")
		)
		(fp_line
			(start -0.7874 0.4064)
			(end -0.7874 -0.4064)
			(stroke
				(width 0.1524)
				(type default)
			)
			(layer "F.SilkS")
		)
		(fp_line
			(start -0.12065 -0.305054)
			(end -0.12065 -0.2794)
			(stroke
				(width 0.1)
				(type default)
			)
			(layer "F.Fab")
		)
		(fp_line
			(start -0.67945 -0.305054)
			(end -0.12065 -0.305054)
			(stroke
				(width 0.1)
				(type default)
			)
			(layer "F.Fab")
		)
		(fp_line
			(start 0.67945 -0.3048)
			(end 0.67945 0.3048)
			(stroke
				(width 0.1)
				(type default)
			)
			(layer "F.Fab")
		)
		(fp_line
			(start 0.12065 -0.3048)
			(end 0.67945 -0.3048)
			(stroke
				(width 0.1)
				(type default)
			)
			(layer "F.Fab")
		)
		(fp_line
			(start 0.12065 -0.2794)
			(end 0.12065 -0.3048)
			(stroke
				(width 0.1)
				(type default)
			)
			(layer "F.Fab")
		)
		(fp_line
			(start -0.12065 -0.2794)
			(end 0.12065 -0.2794)
			(stroke
				(width 0.1)
				(type default)
			)
			(layer "F.Fab")
		)
		(fp_line
			(start 0.120396 0.2794)
			(end -0.12065 0.2794)
			(stroke
				(width 0.1)
				(type default)
			)
			(layer "F.Fab")
		)
		(fp_line
			(start -0.12065 0.2794)
			(end -0.12065 0.3048)
			(stroke
				(width 0.1)
				(type default)
			)
			(layer "F.Fab")
		)
		(fp_line
			(start 0.67945 0.3048)
			(end 0.120396 0.3048)
			(stroke
				(width 0.1)
				(type default)
			)
			(layer "F.Fab")
		)
		(fp_line
			(start 0.120396 0.3048)
			(end 0.120396 0.2794)
			(stroke
				(width 0.1)
				(type default)
			)
			(layer "F.Fab")
		)
		(fp_line
			(start -0.12065 0.3048)
			(end -0.67945 0.3048)
			(stroke
				(width 0.1)
				(type default)
			)
			(layer "F.Fab")
		)
		(fp_line
			(start -0.67945 0.3048)
			(end -0.67945 -0.305054)
			(stroke
				(width 0.1)
				(type default)
			)
			(layer "F.Fab")
		)
		(pad "1" smd circle
			(at -0.40005 0 90)
			(size 0 0)
			(layers "F.Cu" "F.Mask" "F.Paste")
			(net "PVDDCR_CPU1_P1_VCCS")
		)
		(pad "2" smd circle
			(at 0.40005 0 90)
			(size 0 0)
			(layers "F.Cu" "F.Mask" "F.Paste")
			(net "GND")
		)
	)
	(footprint ""
		(layer "F.Cu")
		(at 136.840976 -376.982228)
		(property "Reference" "C51"
			(at 0 0 0)
			(layer "F.SilkS")
			(hide yes)
			(effects
				(font
					(size 1.27 1.27)
				)
			)
		)
		(property "Value" ""
			(at 0 0 0)
			(layer "F.Fab")
			(effects
				(font
					(size 1.27 1.27)
				)
			)
		)
		(duplicate_pad_numbers_are_jumpers no)
		(fp_line
			(start -0.299974 -0.150114)
			(end 0.299974 -0.150114)
			(stroke
				(width 0.1)
				(type default)
			)
			(layer "F.Fab")
		)
		(fp_line
			(start -0.299974 0.150114)
			(end -0.299974 -0.150114)
			(stroke
				(width 0.1)
				(type default)
			)
			(layer "F.Fab")
		)
		(fp_line
			(start 0.299974 -0.150114)
			(end 0.299974 0.150114)
			(stroke
				(width 0.1)
				(type default)
			)
			(layer "F.Fab")
		)
		(fp_line
			(start 0.299974 0.150114)
			(end -0.299974 0.150114)
			(stroke
				(width 0.1)
				(type default)
			)
			(layer "F.Fab")
		)
		(pad "1" smd rect
			(at -0.2667 0)
			(size 0.3048 0.381)
			(layers "F.Cu" "F.Mask" "F.Paste")
			(net "P5E_CPU1_P3_TX_C_DP<14>")
		)
		(pad "2" smd rect
			(at 0.2667 0)
			(size 0.3048 0.381)
			(layers "F.Cu" "F.Mask" "F.Paste")
			(net "P5E_CPU1_P3_TX_DP<14>")
		)
	)
	(footprint ""
		(layer "F.Cu")
		(at 33.722818 -438.084214 -90)
		(property "Reference" "R2986"
			(at 0 0 270)
			(layer "F.SilkS")
			(hide yes)
			(effects
				(font
					(size 1.27 1.27)
				)
			)
		)
		(property "Value" ""
			(at 0 0 270)
			(layer "F.Fab")
			(effects
				(font
					(size 1.27 1.27)
				)
			)
		)
		(duplicate_pad_numbers_are_jumpers no)
		(fp_line
			(start -0.7874 0.4064)
			(end -0.7874 -0.4064)
			(stroke
				(width 0.1524)
				(type default)
			)
			(layer "F.SilkS")
		)
		(fp_line
			(start 0.7874 0.4064)
			(end -0.7874 0.4064)
			(stroke
				(width 0.1524)
				(type default)
			)
			(layer "F.SilkS")
		)
		(fp_line
			(start -0.7874 -0.4064)
			(end 0.7874 -0.4064)
			(stroke
				(width 0.1524)
				(type default)
			)
			(layer "F.SilkS")
		)
		(fp_line
			(start 0.7874 -0.4064)
			(end 0.7874 0.4064)
			(stroke
				(width 0.1524)
				(type default)
			)
			(layer "F.SilkS")
		)
		(fp_line
			(start -0.67945 0.3048)
			(end -0.67945 -0.305054)
			(stroke
				(width 0.1)
				(type default)
			)
			(layer "F.Fab")
		)
		(fp_line
			(start -0.12065 0.3048)
			(end -0.67945 0.3048)
			(stroke
				(width 0.1)
				(type default)
			)
			(layer "F.Fab")
		)
		(fp_line
			(start 0.120396 0.3048)
			(end 0.120396 0.2794)
			(stroke
				(width 0.1)
				(type default)
			)
			(layer "F.Fab")
		)
		(fp_line
			(start 0.67945 0.3048)
			(end 0.120396 0.3048)
			(stroke
				(width 0.1)
				(type default)
			)
			(layer "F.Fab")
		)
		(fp_line
			(start -0.12065 0.2794)
			(end -0.12065 0.3048)
			(stroke
				(width 0.1)
				(type default)
			)
			(layer "F.Fab")
		)
		(fp_line
			(start 0.120396 0.2794)
			(end -0.12065 0.2794)
			(stroke
				(width 0.1)
				(type default)
			)
			(layer "F.Fab")
		)
		(fp_line
			(start -0.12065 -0.2794)
			(end 0.12065 -0.2794)
			(stroke
				(width 0.1)
				(type default)
			)
			(layer "F.Fab")
		)
		(fp_line
			(start 0.12065 -0.2794)
			(end 0.12065 -0.3048)
			(stroke
				(width 0.1)
				(type default)
			)
			(layer "F.Fab")
		)
		(fp_line
			(start 0.12065 -0.3048)
			(end 0.67945 -0.3048)
			(stroke
				(width 0.1)
				(type default)
			)
			(layer "F.Fab")
		)
		(fp_line
			(start 0.67945 -0.3048)
			(end 0.67945 0.3048)
			(stroke
				(width 0.1)
				(type default)
			)
			(layer "F.Fab")
		)
		(fp_line
			(start -0.67945 -0.305054)
			(end -0.12065 -0.305054)
			(stroke
				(width 0.1)
				(type default)
			)
			(layer "F.Fab")
		)
		(fp_line
			(start -0.12065 -0.305054)
			(end -0.12065 -0.2794)
			(stroke
				(width 0.1)
				(type default)
			)
			(layer "F.Fab")
		)
		(pad "1" smd circle
			(at -0.40005 0 270)
			(size 0 0)
			(layers "F.Cu" "F.Mask" "F.Paste")
			(net "SMB_2_BMC_GPU_R_SCL")
		)
		(pad "2" smd circle
			(at 0.40005 0 270)
			(size 0 0)
			(layers "F.Cu" "F.Mask" "F.Paste")
			(net "SMB_2_BMC_GPU_BUF_R_SCL")
		)
	)
)
